(kicad_pcb
	(version 20260206)
	(generator "pcbnew")
	(generator_version "10.0")
	(general
		(thickness 1.6)
		(legacy_teardrops no)
	)
	(paper "A4")
	(title_block
		(title "04192023_DAF0TMB3IC0_F0TG_MB_C_brd_V02_OCP.brd")
		(comment 1 "Grand Teton / footprints 3138-3138 of 8354")
	)
	(layers
		(0 "F.Cu" signal "TOP")
		(4 "In1.Cu" signal "GND")
		(6 "In2.Cu" signal "IN1")
		(8 "In3.Cu" signal "GND1")
		(10 "In4.Cu" signal "IN2")
		(12 "In5.Cu" signal "GND2")
		(14 "In6.Cu" signal "IN3")
		(16 "In7.Cu" signal "GND3")
		(18 "In8.Cu" signal "VCC")
		(20 "In9.Cu" signal "VCC1")
		(22 "In10.Cu" signal "GND4")
		(24 "In11.Cu" signal "IN4")
		(26 "In12.Cu" signal "GND5")
		(28 "In13.Cu" signal "IN5")
		(30 "In14.Cu" signal "GND6")
		(32 "In15.Cu" signal "IN6")
		(34 "In16.Cu" signal "GND7")
		(2 "B.Cu" signal "BOTTOM")
		(9 "F.Adhes" user "F.Adhesive")
		(11 "B.Adhes" user "B.Adhesive")
		(13 "F.Paste" user "Package Geometry/Pastemask Top")
		(15 "B.Paste" user "Package Geometry/Pastemask Bottom")
		(5 "F.SilkS" user "Ref Des/Silkscreen Top")
		(7 "B.SilkS" user "Ref Des/Silkscreen Bottom")
		(1 "F.Mask" user "Board Geometry/Soldermask Top")
		(3 "B.Mask" user "Board Geometry/Soldermask Bottom")
		(17 "Dwgs.User" user "User.Drawings")
		(19 "Cmts.User" user "User.Comments")
		(21 "Eco1.User" user "User.Eco1")
		(23 "Eco2.User" user "User.Eco2")
		(25 "Edge.Cuts" user "Board Geometry/Outline")
		(27 "Margin" user)
		(31 "F.CrtYd" user "Package Geometry/Place Bound Top")
		(29 "B.CrtYd" user "Package Geometry/Place Bound Bottom")
		(35 "F.Fab" user "Ref Des/Assembly Top")
		(33 "B.Fab" user "Ref Des/Assembly Bottom")
	)
	(footprint ""
		(layer "F.Cu")
		(at 234.300014 -50.55997 180)
		(property "Reference" "J90"
			(at 4.181094 -11.365484 90)
			(unlocked yes)
			(layer "F.SilkS")
			(effects
				(font
					(size 0.7874 0.5842)
					(thickness 0.1524)
				)
			)
		)
		(property "Value" ""
			(at 0 0 180)
			(layer "F.Fab")
			(effects
				(font
					(size 1.27 1.27)
				)
			)
		)
		(duplicate_pad_numbers_are_jumpers no)
		(fp_line
			(start 3.150108 12.115038)
			(end 1.529334 12.115038)
			(stroke
				(width 0.1524)
				(type default)
			)
			(layer "F.SilkS")
		)
		(fp_line
			(start 3.150108 7.86003)
			(end 3.150108 12.115038)
			(stroke
				(width 0.1524)
				(type default)
			)
			(layer "F.SilkS")
		)
		(fp_line
			(start 3.150108 5.95503)
			(end 3.150108 6.71703)
			(stroke
				(width 0.1524)
				(type default)
			)
			(layer "F.SilkS")
		)
		(fp_line
			(start 3.150108 4.17703)
			(end 3.150108 4.93903)
			(stroke
				(width 0.1524)
				(type default)
			)
			(layer "F.SilkS")
		)
		(fp_line
			(start 3.150108 2.39903)
			(end 3.150108 3.28803)
			(stroke
				(width 0.1524)
				(type default)
			)
			(layer "F.SilkS")
		)
		(fp_line
			(start 3.150108 -12.115038)
			(end 3.150108 1.38303)
			(stroke
				(width 0.1524)
				(type default)
			)
			(layer "F.SilkS")
		)
		(fp_line
			(start 3.074924 12.014962)
			(end 1.632204 12.014962)
			(stroke
				(width 0.1524)
				(type default)
			)
			(layer "F.SilkS")
		)
		(fp_line
			(start 3.074924 7.86003)
			(end 3.074924 12.014962)
			(stroke
				(width 0.1524)
				(type default)
			)
			(layer "F.SilkS")
		)
		(fp_line
			(start 3.074924 5.95503)
			(end 3.074924 6.71703)
			(stroke
				(width 0.1524)
				(type default)
			)
			(layer "F.SilkS")
		)
		(fp_line
			(start 3.074924 4.17703)
			(end 3.074924 4.93903)
			(stroke
				(width 0.1524)
				(type default)
			)
			(layer "F.SilkS")
		)
		(fp_line
			(start 3.074924 2.39903)
			(end 3.074924 3.28803)
			(stroke
				(width 0.1524)
				(type default)
			)
			(layer "F.SilkS")
		)
		(fp_line
			(start 3.074924 -12.014962)
			(end 3.074924 1.38303)
			(stroke
				(width 0.1524)
				(type default)
			)
			(layer "F.SilkS")
		)
		(fp_line
			(start 1.632204 -12.014962)
			(end 3.074924 -12.014962)
			(stroke
				(width 0.1524)
				(type default)
			)
			(layer "F.SilkS")
		)
		(fp_line
			(start 1.529334 -12.115038)
			(end 3.150108 -12.115038)
			(stroke
				(width 0.1524)
				(type default)
			)
			(layer "F.SilkS")
		)
		(fp_line
			(start -1.529334 12.115038)
			(end -3.150108 12.115038)
			(stroke
				(width 0.1524)
				(type default)
			)
			(layer "F.SilkS")
		)
		(fp_line
			(start -1.632204 12.014962)
			(end -3.074924 12.014962)
			(stroke
				(width 0.1524)
				(type default)
			)
			(layer "F.SilkS")
		)
		(fp_line
			(start -3.074924 12.014962)
			(end -3.074924 7.73303)
			(stroke
				(width 0.1524)
				(type default)
			)
			(layer "F.SilkS")
		)
		(fp_line
			(start -3.074924 6.84403)
			(end -3.074924 5.95503)
			(stroke
				(width 0.1524)
				(type default)
			)
			(layer "F.SilkS")
		)
		(fp_line
			(start -3.074924 4.93903)
			(end -3.074924 4.17703)
			(stroke
				(width 0.1524)
				(type default)
			)
			(layer "F.SilkS")
		)
		(fp_line
			(start -3.074924 3.16103)
			(end -3.074924 2.39903)
			(stroke
				(width 0.1524)
				(type default)
			)
			(layer "F.SilkS")
		)
		(fp_line
			(start -3.074924 1.38303)
			(end -3.074924 0.62103)
			(stroke
				(width 0.1524)
				(type default)
			)
			(layer "F.SilkS")
		)
		(fp_line
			(start -3.074924 -0.52197)
			(end -3.074924 -12.014962)
			(stroke
				(width 0.1524)
				(type default)
			)
			(layer "F.SilkS")
		)
		(fp_line
			(start -3.074924 -12.014962)
			(end -1.632204 -12.014962)
			(stroke
				(width 0.1524)
				(type default)
			)
			(layer "F.SilkS")
		)
		(fp_line
			(start -3.150108 12.115038)
			(end -3.150108 7.73303)
			(stroke
				(width 0.1524)
				(type default)
			)
			(layer "F.SilkS")
		)
		(fp_line
			(start -3.150108 6.84403)
			(end -3.150108 5.95503)
			(stroke
				(width 0.1524)
				(type default)
			)
			(layer "F.SilkS")
		)
		(fp_line
			(start -3.150108 4.93903)
			(end -3.150108 4.17703)
			(stroke
				(width 0.1524)
				(type default)
			)
			(layer "F.SilkS")
		)
		(fp_line
			(start -3.150108 3.16103)
			(end -3.150108 2.39903)
			(stroke
				(width 0.1524)
				(type default)
			)
			(layer "F.SilkS")
		)
		(fp_line
			(start -3.150108 1.38303)
			(end -3.150108 0.62103)
			(stroke
				(width 0.1524)
				(type default)
			)
			(layer "F.SilkS")
		)
		(fp_line
			(start -3.150108 -0.52197)
			(end -3.150108 -12.115038)
			(stroke
				(width 0.1524)
				(type default)
			)
			(layer "F.SilkS")
		)
		(fp_line
			(start -3.150108 -12.115038)
			(end -1.529334 -12.115038)
			(stroke
				(width 0.1524)
				(type default)
			)
			(layer "F.SilkS")
		)
		(fp_poly
			(pts
				(xy 4.798314 -9.23544) (xy 3.530854 -8.812784) (xy 3.953256 -10.080498)
			)
			(stroke
				(width 0)
				(type default)
			)
			(fill yes)
			(layer "F.SilkS")
		)
		(fp_line
			(start 3.074924 12.014962)
			(end -3.074924 12.014962)
			(stroke
				(width 0.1)
				(type default)
			)
			(layer "F.Fab")
		)
		(fp_line
			(start 3.074924 -12.014962)
			(end 3.074924 12.014962)
			(stroke
				(width 0.1)
				(type default)
			)
			(layer "F.Fab")
		)
		(fp_line
			(start -3.074924 12.014962)
			(end -3.074924 -12.014962)
			(stroke
				(width 0.1)
				(type default)
			)
			(layer "F.Fab")
		)
		(fp_line
			(start -3.074924 -12.014962)
			(end 3.074924 -12.014962)
			(stroke
				(width 0.1)
				(type default)
			)
			(layer "F.Fab")
		)
		(fp_poly
			(pts
				(xy 3.348736 -7.994904) (xy 4.543806 -8.592566) (xy 4.543806 -7.397496)
			)
			(stroke
				(width 0)
				(type default)
			)
			(fill yes)
			(layer "F.Fab")
		)
		(pad "" np_thru_hole circle
			(at -1.75006 -9.815068 90)
			(size 1.1176 1.1176)
			(drill 1.1176)
			(layers "*.Cu" "*.Mask")
			(clearance 0.381)
			(thermal_gap 0.381)
		)
		(pad "" np_thru_hole circle
			(at 0 9.815068 90)
			(size 1.1176 1.1176)
			(drill 1.1176)
			(layers "*.Cu" "*.Mask")
			(clearance 0.381)
			(thermal_gap 0.381)
		)
		(pad "A1" smd rect
			(at 2.29997 -7.994904 90)
			(size 0.381 1.27)
			(layers "F.Cu" "F.Mask" "F.Paste")
			(net "GND")
		)
		(pad "A2" smd rect
			(at 2.29997 -7.394956 90)
			(size 0.381 1.27)
			(layers "F.Cu" "F.Mask" "F.Paste")
			(net "GND")
		)
		(pad "A3" smd rect
			(at 2.29997 -6.795008 90)
			(size 0.381 1.27)
			(layers "F.Cu" "F.Mask" "F.Paste")
			(net "GND")
		)
		(pad "A4" smd rect
			(at 2.29997 -6.19506 90)
			(size 0.381 1.27)
			(layers "F.Cu" "F.Mask" "F.Paste")
			(net "GND")
		)
		(pad "A5" smd rect
			(at 2.29997 -5.595112 90)
			(size 0.381 1.27)
			(layers "F.Cu" "F.Mask" "F.Paste")
			(net "GND")
		)
		(pad "A6" smd rect
			(at 2.29997 -4.99491 90)
			(size 0.381 1.27)
			(layers "F.Cu" "F.Mask" "F.Paste")
			(net "GND")
		)
		(pad "A7" smd rect
			(at 2.29997 -4.394962 90)
			(size 0.381 1.27)
			(layers "F.Cu" "F.Mask" "F.Paste")
			(net "SMB_E1S_3V3AUX_ISO_SCL")
		)
		(pad "A8" smd rect
			(at 2.29997 -3.795014 90)
			(size 0.381 1.27)
			(layers "F.Cu" "F.Mask" "F.Paste")
			(net "SMB_E1S_3V3AUX_ISO_SDA")
		)
		(pad "A9" smd rect
			(at 2.29997 -3.195066 90)
			(size 0.381 1.27)
			(layers "F.Cu" "F.Mask" "F.Paste")
			(net "RST_SMB_E1S_0_N")
		)
		(pad "A10" smd rect
			(at 2.29997 -2.595118 90)
			(size 0.381 1.27)
			(layers "F.Cu" "F.Mask" "F.Paste")
			(net "FM_LED_ACTIVE_E1S_0_BUF")
		)
		(pad "A11" smd rect
			(at 2.29997 -1.994916 90)
			(size 0.381 1.27)
			(layers "F.Cu" "F.Mask" "F.Paste")
			(net "E1S_0_PERST1_CLKREQ_N")
		)
		(pad "A12" smd rect
			(at 2.29997 -1.394968 90)
			(size 0.381 1.27)
			(layers "F.Cu" "F.Mask" "F.Paste")
			(net "E1S_0_PRSNT_N")
		)
		(pad "A13" smd rect
			(at 2.29997 -0.79502 90)
			(size 0.381 1.27)
			(layers "F.Cu" "F.Mask" "F.Paste")
			(net "GND")
		)
		(pad "A14" smd rect
			(at 2.29997 -0.195072 90)
			(size 0.381 1.27)
			(layers "F.Cu" "F.Mask" "F.Paste")
			(net "TP_CLK_100M_E1S_0_DN")
		)
		(pad "A15" smd rect
			(at 2.29997 0.404876 90)
			(size 0.381 1.27)
			(layers "F.Cu" "F.Mask" "F.Paste")
			(net "TP_CLK_100M_E1S_0_DP")
		)
		(pad "A16" smd rect
			(at 2.29997 1.005078 90)
			(size 0.381 1.27)
			(layers "F.Cu" "F.Mask" "F.Paste")
			(net "GND")
		)
		(pad "A17" smd rect
			(at 2.29997 1.605026 90)
			(size 0.381 1.27)
			(layers "F.Cu" "F.Mask" "F.Paste")
			(net "P3E_CPU0_P4_RX_DP<0>")
		)
		(pad "A18" smd rect
			(at 2.29997 2.204974 90)
			(size 0.381 1.27)
			(layers "F.Cu" "F.Mask" "F.Paste")
			(net "P3E_CPU0_P4_RX_DN<0>")
		)
		(pad "A19" smd rect
			(at 2.29997 2.804922 90)
			(size 0.381 1.27)
			(layers "F.Cu" "F.Mask" "F.Paste")
			(net "GND")
		)
		(pad "A20" smd rect
			(at 2.29997 3.405124 90)
			(size 0.381 1.27)
			(layers "F.Cu" "F.Mask" "F.Paste")
			(net "P3E_CPU0_P4_RX_DP<1>")
		)
		(pad "A21" smd rect
			(at 2.29997 4.005072 90)
			(size 0.381 1.27)
			(layers "F.Cu" "F.Mask" "F.Paste")
			(net "P3E_CPU0_P4_RX_DN<1>")
		)
		(pad "A22" smd rect
			(at 2.29997 4.60502 90)
			(size 0.381 1.27)
			(layers "F.Cu" "F.Mask" "F.Paste")
			(net "GND")
		)
		(pad "A23" smd rect
			(at 2.29997 5.204968 90)
			(size 0.381 1.27)
			(layers "F.Cu" "F.Mask" "F.Paste")
			(net "P3E_CPU0_P4_RX_DP<2>")
		)
		(pad "A24" smd rect
			(at 2.29997 5.804916 90)
			(size 0.381 1.27)
			(layers "F.Cu" "F.Mask" "F.Paste")
			(net "P3E_CPU0_P4_RX_DN<2>")
		)
		(pad "A25" smd rect
			(at 2.29997 6.405118 90)
			(size 0.381 1.27)
			(layers "F.Cu" "F.Mask" "F.Paste")
			(net "GND")
		)
		(pad "A26" smd rect
			(at 2.29997 7.005066 90)
			(size 0.381 1.27)
			(layers "F.Cu" "F.Mask" "F.Paste")
			(net "P3E_CPU0_P4_RX_DP<3>")
		)
		(pad "A27" smd rect
			(at 2.29997 7.605014 90)
			(size 0.381 1.27)
			(layers "F.Cu" "F.Mask" "F.Paste")
			(net "P3E_CPU0_P4_RX_DN<3>")
		)
		(pad "A28" smd rect
			(at 2.29997 8.204962 90)
			(size 0.381 1.27)
			(layers "F.Cu" "F.Mask" "F.Paste")
			(net "GND")
		)
		(pad "B1" smd rect
			(at -2.29997 -7.994904 90)
			(size 0.381 1.27)
			(layers "F.Cu" "F.Mask" "F.Paste")
			(net "P12V_E1S_0_R")
		)
		(pad "B2" smd rect
			(at -2.29997 -7.394956 90)
			(size 0.381 1.27)
			(layers "F.Cu" "F.Mask" "F.Paste")
			(net "P12V_E1S_0_R")
		)
		(pad "B3" smd rect
			(at -2.29997 -6.795008 90)
			(size 0.381 1.27)
			(layers "F.Cu" "F.Mask" "F.Paste")
			(net "P12V_E1S_0_R")
		)
		(pad "B4" smd rect
			(at -2.29997 -6.19506 90)
			(size 0.381 1.27)
			(layers "F.Cu" "F.Mask" "F.Paste")
			(net "P12V_E1S_0_R")
		)
		(pad "B5" smd rect
			(at -2.29997 -5.595112 90)
			(size 0.381 1.27)
			(layers "F.Cu" "F.Mask" "F.Paste")
			(net "P12V_E1S_0_R")
		)
		(pad "B6" smd rect
			(at -2.29997 -4.99491 90)
			(size 0.381 1.27)
			(layers "F.Cu" "F.Mask" "F.Paste")
			(net "P12V_E1S_0_R")
		)
		(pad "B7" smd rect
			(at -2.29997 -4.394962 90)
			(size 0.381 1.27)
			(layers "F.Cu" "F.Mask" "F.Paste")
			(net "TP_E1S_0_MFG")
		)
		(pad "B8" smd rect
			(at -2.29997 -3.795014 90)
			(size 0.381 1.27)
			(layers "F.Cu" "F.Mask" "F.Paste")
			(net "TP_E1S_0_RFU")
		)
		(pad "B9" smd rect
			(at -2.29997 -3.195066 90)
			(size 0.381 1.27)
			(layers "F.Cu" "F.Mask" "F.Paste")
			(net "PU_E1S_0_DUALPORT_EN_N")
		)
		(pad "B10" smd rect
			(at -2.29997 -2.595118 90)
			(size 0.381 1.27)
			(layers "F.Cu" "F.Mask" "F.Paste")
			(net "RST_PCIE_E1S_PERST_N")
		)
		(pad "B11" smd rect
			(at -2.29997 -1.994916 90)
			(size 0.381 1.27)
			(layers "F.Cu" "F.Mask" "F.Paste")
			(net "P3V3_E1S_0")
		)
		(pad "B12" smd rect
			(at -2.29997 -1.394968 90)
			(size 0.381 1.27)
			(layers "F.Cu" "F.Mask" "F.Paste")
			(net "E1S_0_PWRDIS")
		)
		(pad "B13" smd rect
			(at -2.29997 -0.79502 90)
			(size 0.381 1.27)
			(layers "F.Cu" "F.Mask" "F.Paste")
			(net "GND")
		)
		(pad "B14" smd rect
			(at -2.29997 -0.195072 90)
			(size 0.381 1.27)
			(layers "F.Cu" "F.Mask" "F.Paste")
			(net "CLK_100M_CPU0_CLK12_DN")
		)
		(pad "B15" smd rect
			(at -2.29997 0.404876 90)
			(size 0.381 1.27)
			(layers "F.Cu" "F.Mask" "F.Paste")
			(net "CLK_100M_CPU0_CLK12_DP")
		)
		(pad "B16" smd rect
			(at -2.29997 1.005078 90)
			(size 0.381 1.27)
			(layers "F.Cu" "F.Mask" "F.Paste")
			(net "GND")
		)
		(pad "B17" smd rect
			(at -2.29997 1.605026 90)
			(size 0.381 1.27)
			(layers "F.Cu" "F.Mask" "F.Paste")
			(net "P3E_CPU0_P4_TX_C_DP<0>")
		)
		(pad "B18" smd rect
			(at -2.29997 2.204974 90)
			(size 0.381 1.27)
			(layers "F.Cu" "F.Mask" "F.Paste")
			(net "P3E_CPU0_P4_TX_C_DN<0>")
		)
		(pad "B19" smd rect
			(at -2.29997 2.804922 90)
			(size 0.381 1.27)
			(layers "F.Cu" "F.Mask" "F.Paste")
			(net "GND")
		)
		(pad "B20" smd rect
			(at -2.29997 3.405124 90)
			(size 0.381 1.27)
			(layers "F.Cu" "F.Mask" "F.Paste")
			(net "P3E_CPU0_P4_TX_C_DP<1>")
		)
		(pad "B21" smd rect
			(at -2.29997 4.005072 90)
			(size 0.381 1.27)
			(layers "F.Cu" "F.Mask" "F.Paste")
			(net "P3E_CPU0_P4_TX_C_DN<1>")
		)
		(pad "B22" smd rect
			(at -2.29997 4.60502 90)
			(size 0.381 1.27)
			(layers "F.Cu" "F.Mask" "F.Paste")
			(net "GND")
		)
		(pad "B23" smd rect
			(at -2.29997 5.204968 90)
			(size 0.381 1.27)
			(layers "F.Cu" "F.Mask" "F.Paste")
			(net "P3E_CPU0_P4_TX_C_DP<2>")
		)
		(pad "B24" smd rect
			(at -2.29997 5.804916 90)
			(size 0.381 1.27)
			(layers "F.Cu" "F.Mask" "F.Paste")
			(net "P3E_CPU0_P4_TX_C_DN<2>")
		)
		(pad "B25" smd rect
			(at -2.29997 6.405118 90)
			(size 0.381 1.27)
			(layers "F.Cu" "F.Mask" "F.Paste")
			(net "GND")
		)
		(pad "B26" smd rect
			(at -2.29997 7.005066 90)
			(size 0.381 1.27)
			(layers "F.Cu" "F.Mask" "F.Paste")
			(net "P3E_CPU0_P4_TX_C_DN<3>")
		)
		(pad "B27" smd rect
			(at -2.29997 7.605014 90)
			(size 0.381 1.27)
			(layers "F.Cu" "F.Mask" "F.Paste")
			(net "P3E_CPU0_P4_TX_C_DP<3>")
		)
		(pad "B28" smd rect
			(at -2.29997 8.204962 90)
			(size 0.381 1.27)
			(layers "F.Cu" "F.Mask" "F.Paste")
			(net "GND")
		)
		(pad "G1" thru_hole oval
			(at 0 -11.364976 90)
			(size 1.6256 3.4798)
			(drill oval 1.1176 2.4638)
			(layers "*.Cu" "*.Mask")
			(remove_unused_layers no)
			(net "GND")
			(clearance 0.127)
			(thermal_gap 0.127)
		)
		(pad "G2" thru_hole oval
			(at 0 11.364976 90)
			(size 1.6256 3.4798)
			(drill oval 1.1176 2.4638)
			(layers "*.Cu" "*.Mask")
			(remove_unused_layers no)
			(net "GND")
			(clearance 0.127)
			(thermal_gap 0.127)
		)
		(zone
			(layer "F.Cu")
			(hatch none 0.5)
			(connect_pads
				(clearance 0)
			)
			(min_thickness 0.25)
			(keepout
				(tracks not_allowed)
				(vias allowed)
				(pads allowed)
				(copperpour not_allowed)
				(footprints allowed)
			)
			(placement
				(enabled no)
				(sheetname "")
			)
			(fill
				(thermal_gap 0.5)
				(thermal_bridge_width 0.5)
				(island_removal_mode 0)
			)
			(polygon
				(pts
					(xy 232.920032 -38.49497) (xy 236.750098 -38.49497) (xy 236.750098 -41.444926) (xy 232.920032 -41.444926)
				)
			)
		)
		(zone
			(layer "F.Cu")
			(hatch none 0.5)
			(connect_pads
				(clearance 0)
			)
			(min_thickness 0.25)
			(keepout
				(tracks not_allowed)
				(vias allowed)
				(pads allowed)
				(copperpour not_allowed)
				(footprints allowed)
			)
			(placement
				(enabled no)
				(sheetname "")
			)
			(fill
				(thermal_gap 0.5)
				(thermal_bridge_width 0.5)
				(island_removal_mode 0)
			)
			(polygon
				(pts
					(xy 232.929938 -59.675014) (xy 235.679996 -59.675014) (xy 235.679996 -62.62497) (xy 232.929938 -62.62497)
				)
			)
		)
		(zone
			(layers "F.Cu" "B.Cu" "In1.Cu" "In2.Cu" "In3.Cu" "In4.Cu" "In5.Cu" "In6.Cu"
				"In7.Cu" "In8.Cu" "In9.Cu" "In10.Cu" "In11.Cu" "In12.Cu" "In13.Cu" "In14.Cu"
				"In15.Cu" "In16.Cu"
			)
			(hatch none 0.5)
			(connect_pads
				(clearance 0)
			)
			(min_thickness 0.25)
			(keepout
				(tracks not_allowed)
				(vias allowed)
				(pads allowed)
				(copperpour not_allowed)
				(footprints allowed)
			)
			(placement
				(enabled no)
				(sheetname "")
			)
			(fill
				(thermal_gap 0.5)
				(thermal_bridge_width 0.5)
				(island_removal_mode 0)
			)
			(polygon
				(pts
					(arc
						(start 235.265214 -60.375038)
						(mid 233.334814 -60.375038)
						(end 235.265214 -60.375038)
					)
				)
			)
		)
		(zone
			(layers "F.Cu" "B.Cu" "In1.Cu" "In2.Cu" "In3.Cu" "In4.Cu" "In5.Cu" "In6.Cu"
				"In7.Cu" "In8.Cu" "In9.Cu" "In10.Cu" "In11.Cu" "In12.Cu" "In13.Cu" "In14.Cu"
				"In15.Cu" "In16.Cu"
			)
			(hatch none 0.5)
			(connect_pads
				(clearance 0)
			)
			(min_thickness 0.25)
			(keepout
				(tracks not_allowed)
				(vias allowed)
				(pads allowed)
				(copperpour not_allowed)
				(footprints allowed)
			)
			(placement
				(enabled no)
				(sheetname "")
			)
			(fill
				(thermal_gap 0.5)
				(thermal_bridge_width 0.5)
				(island_removal_mode 0)
			)
			(polygon
				(pts
					(arc
						(start 237.015274 -40.744902)
						(mid 235.084874 -40.744902)
						(end 237.015274 -40.744902)
					)
				)
			)
		)
	)
)
